# S9S_MB_2U (Grand Teton) — schematic netlist excerpt (pin names and nets, part order shuffled) for the footprints in the layout excerpt that follows; sources: Cadence DE-HDL packaged netlist, KiCad conversion of 03242023_DA0F0TMBIJ0_F0T_Motherboard_J_brd_V01_OCP.brd

PC2344  Q_CAP  22UF 16V 20% X6S  pkg C0805  page 259 : A = SW_P3V3_AUX_FLT ; B = GND
R4809  Q_RES  0 5% CHIP  pkg 0402LF  page 240 : A = FM_BMC_INTRUDER_N ; B = GND
R1328  Q_RES  2K 1% EMPTY  pkg 0402LF  page 219 : A = PWRGD_DRAMPWRGD_CPU0_GH_R_LVC1 ; B = GND

(kicad_pcb
	(version 20260206)
	(generator "pcbnew")
	(generator_version "10.0")
	(general
		(thickness 1.6)
		(legacy_teardrops no)
	)
	(paper "A4")
	(title_block
		(title "03242023_DA0F0TMBIJ0_F0T_Motherboard_J_brd_V01_OCP.brd")
		(comment 1 "Grand Teton / footprints 5748-5750 of 6105")
	)
	(layers
		(0 "F.Cu" signal "TOP")
		(4 "In1.Cu" signal "GND")
		(6 "In2.Cu" signal "IN1")
		(8 "In3.Cu" signal "GND1")
		(10 "In4.Cu" signal "IN2")
		(12 "In5.Cu" signal "GND2")
		(14 "In6.Cu" signal "IN3")
		(16 "In7.Cu" signal "GND3")
		(18 "In8.Cu" signal "VCC")
		(20 "In9.Cu" signal "VCC1")
		(22 "In10.Cu" signal "GND4")
		(24 "In11.Cu" signal "IN4")
		(26 "In12.Cu" signal "GND5")
		(28 "In13.Cu" signal "IN5")
		(30 "In14.Cu" signal "GND6")
		(32 "In15.Cu" signal "IN6")
		(34 "In16.Cu" signal "GND7")
		(2 "B.Cu" signal "BOTTOM")
		(9 "F.Adhes" user "F.Adhesive")
		(11 "B.Adhes" user "B.Adhesive")
		(13 "F.Paste" user "Package Geometry/Pastemask Top")
		(15 "B.Paste" user "Package Geometry/Pastemask Bottom")
		(5 "F.SilkS" user "Ref Des/Silkscreen Top")
		(7 "B.SilkS" user "Ref Des/Silkscreen Bottom")
		(1 "F.Mask" user "Board Geometry/Soldermask Top")
		(3 "B.Mask" user "Board Geometry/Soldermask Bottom")
		(17 "Dwgs.User" user "User.Drawings")
		(19 "Cmts.User" user "User.Comments")
		(21 "Eco1.User" user "User.Eco1")
		(23 "Eco2.User" user "User.Eco2")
		(25 "Edge.Cuts" user "Board Geometry/Outline")
		(27 "Margin" user)
		(31 "F.CrtYd" user "Package Geometry/Place Bound Top")
		(29 "B.CrtYd" user "Package Geometry/Place Bound Bottom")
		(35 "F.Fab" user "Ref Des/Assembly Top")
		(33 "B.Fab" user "Ref Des/Assembly Bottom")
	)
	(footprint ""
		(layer "B.Cu")
		(at 454.74128 -76.589128 -90)
		(property "Reference" "PC2344"
			(at 0 0 90)
			(layer "B.SilkS")
			(hide yes)
			(effects
				(font
					(size 1.27 1.27)
				)
				(justify mirror)
			)
		)
		(property "Value" ""
			(at 0 0 90)
			(layer "B.Fab")
			(effects
				(font
					(size 1.27 1.27)
				)
				(justify mirror)
			)
		)
		(duplicate_pad_numbers_are_jumpers no)
		(fp_line
			(start -1.524 0.762)
			(end 1.524 0.762)
			(stroke
				(width 0.1524)
				(type default)
			)
			(layer "B.SilkS")
		)
		(fp_line
			(start 1.524 0.762)
			(end 1.524 -0.762)
			(stroke
				(width 0.1524)
				(type default)
			)
			(layer "B.SilkS")
		)
		(fp_line
			(start -1.524 -0.762)
			(end -1.524 0.762)
			(stroke
				(width 0.1524)
				(type default)
			)
			(layer "B.SilkS")
		)
		(fp_line
			(start 1.524 -0.762)
			(end -1.524 -0.762)
			(stroke
				(width 0.1524)
				(type default)
			)
			(layer "B.SilkS")
		)
		(fp_line
			(start -1.1049 0.724916)
			(end -1.1049 -0.724916)
			(stroke
				(width 0.1)
				(type default)
			)
			(layer "B.Fab")
		)
		(fp_line
			(start 1.1049 0.724916)
			(end -1.1049 0.724916)
			(stroke
				(width 0.1)
				(type default)
			)
			(layer "B.Fab")
		)
		(fp_line
			(start -1.1049 -0.724916)
			(end 1.1049 -0.724916)
			(stroke
				(width 0.1)
				(type default)
			)
			(layer "B.Fab")
		)
		(fp_line
			(start 1.1049 -0.724916)
			(end 1.1049 0.724916)
			(stroke
				(width 0.1)
				(type default)
			)
			(layer "B.Fab")
		)
		(pad "1" smd rect
			(at 0.889 0 270)
			(size 1.016 1.27)
			(layers "B.Cu" "B.Mask" "B.Paste")
			(net "SW_P3V3_AUX_FLT")
		)
		(pad "2" smd rect
			(at -0.889 0 270)
			(size 1.016 1.27)
			(layers "B.Cu" "B.Mask" "B.Paste")
			(net "GND")
		)
	)
	(footprint ""
		(layer "B.Cu")
		(at 181.875938 -104.716326 180)
		(property "Reference" "R1328"
			(at 0 0 0)
			(layer "B.SilkS")
			(hide yes)
			(effects
				(font
					(size 1.27 1.27)
				)
				(justify mirror)
			)
		)
		(property "Value" ""
			(at 0 0 0)
			(layer "B.Fab")
			(effects
				(font
					(size 1.27 1.27)
				)
				(justify mirror)
			)
		)
		(duplicate_pad_numbers_are_jumpers no)
		(fp_line
			(start 0.7874 0.4064)
			(end 0.7874 -0.4064)
			(stroke
				(width 0.1524)
				(type default)
			)
			(layer "B.SilkS")
		)
		(fp_line
			(start 0.7874 -0.4064)
			(end -0.7874 -0.4064)
			(stroke
				(width 0.1524)
				(type default)
			)
			(layer "B.SilkS")
		)
		(fp_line
			(start -0.7874 0.4064)
			(end 0.7874 0.4064)
			(stroke
				(width 0.1524)
				(type default)
			)
			(layer "B.SilkS")
		)
		(fp_line
			(start -0.7874 -0.4064)
			(end -0.7874 0.4064)
			(stroke
				(width 0.1524)
				(type default)
			)
			(layer "B.SilkS")
		)
		(fp_line
			(start 0.67945 0.3048)
			(end 0.67945 -0.305054)
			(stroke
				(width 0.1)
				(type default)
			)
			(layer "B.Fab")
		)
		(fp_line
			(start 0.67945 -0.305054)
			(end 0.12065 -0.305054)
			(stroke
				(width 0.1)
				(type default)
			)
			(layer "B.Fab")
		)
		(fp_line
			(start 0.12065 0.3048)
			(end 0.67945 0.3048)
			(stroke
				(width 0.1)
				(type default)
			)
			(layer "B.Fab")
		)
		(fp_line
			(start 0.12065 0.2794)
			(end 0.12065 0.3048)
			(stroke
				(width 0.1)
				(type default)
			)
			(layer "B.Fab")
		)
		(fp_line
			(start 0.12065 -0.2794)
			(end -0.12065 -0.2794)
			(stroke
				(width 0.1)
				(type default)
			)
			(layer "B.Fab")
		)
		(fp_line
			(start 0.12065 -0.305054)
			(end 0.12065 -0.2794)
			(stroke
				(width 0.1)
				(type default)
			)
			(layer "B.Fab")
		)
		(fp_line
			(start -0.120396 0.3048)
			(end -0.120396 0.2794)
			(stroke
				(width 0.1)
				(type default)
			)
			(layer "B.Fab")
		)
		(fp_line
			(start -0.120396 0.2794)
			(end 0.12065 0.2794)
			(stroke
				(width 0.1)
				(type default)
			)
			(layer "B.Fab")
		)
		(fp_line
			(start -0.12065 -0.2794)
			(end -0.12065 -0.3048)
			(stroke
				(width 0.1)
				(type default)
			)
			(layer "B.Fab")
		)
		(fp_line
			(start -0.12065 -0.3048)
			(end -0.67945 -0.3048)
			(stroke
				(width 0.1)
				(type default)
			)
			(layer "B.Fab")
		)
		(fp_line
			(start -0.67945 0.3048)
			(end -0.120396 0.3048)
			(stroke
				(width 0.1)
				(type default)
			)
			(layer "B.Fab")
		)
		(fp_line
			(start -0.67945 -0.3048)
			(end -0.67945 0.3048)
			(stroke
				(width 0.1)
				(type default)
			)
			(layer "B.Fab")
		)
		(pad "1" smd circle
			(at 0.40005 0)
			(size 0 0)
			(layers "B.Cu" "B.Mask" "B.Paste")
			(net "PWRGD_DRAMPWRGD_CPU0_GH_R_LVC1")
		)
		(pad "2" smd circle
			(at -0.40005 0)
			(size 0 0)
			(layers "B.Cu" "B.Mask" "B.Paste")
			(net "GND")
		)
	)
	(footprint ""
		(layer "B.Cu")
		(at 139.346686 -9.362948 90)
		(property "Reference" "R4809"
			(at 0 0 90)
			(layer "B.SilkS")
			(hide yes)
			(effects
				(font
					(size 1.27 1.27)
				)
				(justify mirror)
			)
		)
		(property "Value" ""
			(at 0 0 90)
			(layer "B.Fab")
			(effects
				(font
					(size 1.27 1.27)
				)
				(justify mirror)
			)
		)
		(duplicate_pad_numbers_are_jumpers no)
		(fp_line
			(start 0.7874 -0.4064)
			(end -0.7874 -0.4064)
			(stroke
				(width 0.1524)
				(type default)
			)
			(layer "B.SilkS")
		)
		(fp_line
			(start -0.7874 -0.4064)
			(end -0.7874 0.4064)
			(stroke
				(width 0.1524)
				(type default)
			)
			(layer "B.SilkS")
		)
		(fp_line
			(start 0.7874 0.4064)
			(end 0.7874 -0.4064)
			(stroke
				(width 0.1524)
				(type default)
			)
			(layer "B.SilkS")
		)
		(fp_line
			(start -0.7874 0.4064)
			(end 0.7874 0.4064)
			(stroke
				(width 0.1524)
				(type default)
			)
			(layer "B.SilkS")
		)
		(fp_line
			(start 0.67945 -0.305054)
			(end 0.12065 -0.305054)
			(stroke
				(width 0.1)
				(type default)
			)
			(layer "B.Fab")
		)
		(fp_line
			(start 0.12065 -0.305054)
			(end 0.12065 -0.2794)
			(stroke
				(width 0.1)
				(type default)
			)
			(layer "B.Fab")
		)
		(fp_line
			(start -0.12065 -0.3048)
			(end -0.67945 -0.3048)
			(stroke
				(width 0.1)
				(type default)
			)
			(layer "B.Fab")
		)
		(fp_line
			(start -0.67945 -0.3048)
			(end -0.67945 0.3048)
			(stroke
				(width 0.1)
				(type default)
			)
			(layer "B.Fab")
		)
		(fp_line
			(start 0.12065 -0.2794)
			(end -0.12065 -0.2794)
			(stroke
				(width 0.1)
				(type default)
			)
			(layer "B.Fab")
		)
		(fp_line
			(start -0.12065 -0.2794)
			(end -0.12065 -0.3048)
			(stroke
				(width 0.1)
				(type default)
			)
			(layer "B.Fab")
		)
		(fp_line
			(start 0.12065 0.2794)
			(end 0.12065 0.3048)
			(stroke
				(width 0.1)
				(type default)
			)
			(layer "B.Fab")
		)
		(fp_line
			(start -0.120396 0.2794)
			(end 0.12065 0.2794)
			(stroke
				(width 0.1)
				(type default)
			)
			(layer "B.Fab")
		)
		(fp_line
			(start 0.67945 0.3048)
			(end 0.67945 -0.305054)
			(stroke
				(width 0.1)
				(type default)
			)
			(layer "B.Fab")
		)
		(fp_line
			(start 0.12065 0.3048)
			(end 0.67945 0.3048)
			(stroke
				(width 0.1)
				(type default)
			)
			(layer "B.Fab")
		)
		(fp_line
			(start -0.120396 0.3048)
			(end -0.120396 0.2794)
			(stroke
				(width 0.1)
				(type default)
			)
			(layer "B.Fab")
		)
		(fp_line
			(start -0.67945 0.3048)
			(end -0.120396 0.3048)
			(stroke
				(width 0.1)
				(type default)
			)
			(layer "B.Fab")
		)
		(pad "1" smd circle
			(at 0.40005 0 270)
			(size 0 0)
			(layers "B.Cu" "B.Mask" "B.Paste")
			(net "FM_BMC_INTRUDER_N")
		)
		(pad "2" smd circle
			(at -0.40005 0 270)
			(size 0 0)
			(layers "B.Cu" "B.Mask" "B.Paste")
			(net "GND")
		)
	)
)
